(kicad_pcb
	(version 20260206)
	(generator "pcbnew")
	(generator_version "10.0")
	(general
		(thickness 1.6)
		(legacy_teardrops no)
	)
	(paper "A4")
	(title_block
		(title "03242023_DA0F0TMBIJ0_F0T_Motherboard_J_brd_V01_OCP.brd")
		(comment 1 "Grand Teton / footprints 747-752 of 6105")
	)
	(layers
		(0 "F.Cu" signal "TOP")
		(4 "In1.Cu" signal "GND")
		(6 "In2.Cu" signal "IN1")
		(8 "In3.Cu" signal "GND1")
		(10 "In4.Cu" signal "IN2")
		(12 "In5.Cu" signal "GND2")
		(14 "In6.Cu" signal "IN3")
		(16 "In7.Cu" signal "GND3")
		(18 "In8.Cu" signal "VCC")
		(20 "In9.Cu" signal "VCC1")
		(22 "In10.Cu" signal "GND4")
		(24 "In11.Cu" signal "IN4")
		(26 "In12.Cu" signal "GND5")
		(28 "In13.Cu" signal "IN5")
		(30 "In14.Cu" signal "GND6")
		(32 "In15.Cu" signal "IN6")
		(34 "In16.Cu" signal "GND7")
		(2 "B.Cu" signal "BOTTOM")
		(9 "F.Adhes" user "F.Adhesive")
		(11 "B.Adhes" user "B.Adhesive")
		(13 "F.Paste" user "Package Geometry/Pastemask Top")
		(15 "B.Paste" user "Package Geometry/Pastemask Bottom")
		(5 "F.SilkS" user "Ref Des/Silkscreen Top")
		(7 "B.SilkS" user "Ref Des/Silkscreen Bottom")
		(1 "F.Mask" user "Board Geometry/Soldermask Top")
		(3 "B.Mask" user "Board Geometry/Soldermask Bottom")
		(17 "Dwgs.User" user "User.Drawings")
		(19 "Cmts.User" user "User.Comments")
		(21 "Eco1.User" user "User.Eco1")
		(23 "Eco2.User" user "User.Eco2")
		(25 "Edge.Cuts" user "Board Geometry/Outline")
		(27 "Margin" user)
		(31 "F.CrtYd" user "Package Geometry/Place Bound Top")
		(29 "B.CrtYd" user "Package Geometry/Place Bound Bottom")
		(35 "F.Fab" user "Ref Des/Assembly Top")
		(33 "B.Fab" user "Ref Des/Assembly Bottom")
	)
	(footprint ""
		(layer "F.Cu")
		(at 125.205744 -66.867278 90)
		(property "Reference" "R803"
			(at 0 0 90)
			(layer "F.SilkS")
			(hide yes)
			(effects
				(font
					(size 1.27 1.27)
				)
			)
		)
		(property "Value" ""
			(at 0 0 90)
			(layer "F.Fab")
			(effects
				(font
					(size 1.27 1.27)
				)
			)
		)
		(duplicate_pad_numbers_are_jumpers no)
		(fp_line
			(start 0.7874 -0.4064)
			(end 0.7874 0.4064)
			(stroke
				(width 0.1524)
				(type default)
			)
			(layer "F.SilkS")
		)
		(fp_line
			(start -0.7874 -0.4064)
			(end 0.7874 -0.4064)
			(stroke
				(width 0.1524)
				(type default)
			)
			(layer "F.SilkS")
		)
		(fp_line
			(start 0.7874 0.4064)
			(end -0.7874 0.4064)
			(stroke
				(width 0.1524)
				(type default)
			)
			(layer "F.SilkS")
		)
		(fp_line
			(start -0.7874 0.4064)
			(end -0.7874 -0.4064)
			(stroke
				(width 0.1524)
				(type default)
			)
			(layer "F.SilkS")
		)
		(fp_line
			(start -0.12065 -0.305054)
			(end -0.12065 -0.2794)
			(stroke
				(width 0.1)
				(type default)
			)
			(layer "F.Fab")
		)
		(fp_line
			(start -0.67945 -0.305054)
			(end -0.12065 -0.305054)
			(stroke
				(width 0.1)
				(type default)
			)
			(layer "F.Fab")
		)
		(fp_line
			(start 0.67945 -0.3048)
			(end 0.67945 0.3048)
			(stroke
				(width 0.1)
				(type default)
			)
			(layer "F.Fab")
		)
		(fp_line
			(start 0.12065 -0.3048)
			(end 0.67945 -0.3048)
			(stroke
				(width 0.1)
				(type default)
			)
			(layer "F.Fab")
		)
		(fp_line
			(start 0.12065 -0.2794)
			(end 0.12065 -0.3048)
			(stroke
				(width 0.1)
				(type default)
			)
			(layer "F.Fab")
		)
		(fp_line
			(start -0.12065 -0.2794)
			(end 0.12065 -0.2794)
			(stroke
				(width 0.1)
				(type default)
			)
			(layer "F.Fab")
		)
		(fp_line
			(start 0.120396 0.2794)
			(end -0.12065 0.2794)
			(stroke
				(width 0.1)
				(type default)
			)
			(layer "F.Fab")
		)
		(fp_line
			(start -0.12065 0.2794)
			(end -0.12065 0.3048)
			(stroke
				(width 0.1)
				(type default)
			)
			(layer "F.Fab")
		)
		(fp_line
			(start 0.67945 0.3048)
			(end 0.120396 0.3048)
			(stroke
				(width 0.1)
				(type default)
			)
			(layer "F.Fab")
		)
		(fp_line
			(start 0.120396 0.3048)
			(end 0.120396 0.2794)
			(stroke
				(width 0.1)
				(type default)
			)
			(layer "F.Fab")
		)
		(fp_line
			(start -0.12065 0.3048)
			(end -0.67945 0.3048)
			(stroke
				(width 0.1)
				(type default)
			)
			(layer "F.Fab")
		)
		(fp_line
			(start -0.67945 0.3048)
			(end -0.67945 -0.305054)
			(stroke
				(width 0.1)
				(type default)
			)
			(layer "F.Fab")
		)
		(pad "1" smd circle
			(at -0.40005 0 90)
			(size 0 0)
			(layers "F.Cu" "F.Mask" "F.Paste")
			(net "JTAG_PLD_TDI_R")
		)
		(pad "2" smd circle
			(at 0.40005 0 90)
			(size 0 0)
			(layers "F.Cu" "F.Mask" "F.Paste")
			(net "JTAG_BMC_PLD_TDI")
		)
	)
	(footprint ""
		(layer "F.Cu")
		(at 299.02023 -53.384196 180)
		(property "Reference" "R2977"
			(at 0 0 180)
			(layer "F.SilkS")
			(hide yes)
			(effects
				(font
					(size 1.27 1.27)
				)
			)
		)
		(property "Value" ""
			(at 0 0 180)
			(layer "F.Fab")
			(effects
				(font
					(size 1.27 1.27)
				)
			)
		)
		(duplicate_pad_numbers_are_jumpers no)
		(fp_line
			(start 0.7874 0.4064)
			(end -0.7874 0.4064)
			(stroke
				(width 0.1524)
				(type default)
			)
			(layer "F.SilkS")
		)
		(fp_line
			(start 0.7874 -0.4064)
			(end 0.7874 0.4064)
			(stroke
				(width 0.1524)
				(type default)
			)
			(layer "F.SilkS")
		)
		(fp_line
			(start -0.7874 0.4064)
			(end -0.7874 -0.4064)
			(stroke
				(width 0.1524)
				(type default)
			)
			(layer "F.SilkS")
		)
		(fp_line
			(start -0.7874 -0.4064)
			(end 0.7874 -0.4064)
			(stroke
				(width 0.1524)
				(type default)
			)
			(layer "F.SilkS")
		)
		(fp_line
			(start 0.67945 0.3048)
			(end 0.120396 0.3048)
			(stroke
				(width 0.1)
				(type default)
			)
			(layer "F.Fab")
		)
		(fp_line
			(start 0.67945 -0.3048)
			(end 0.67945 0.3048)
			(stroke
				(width 0.1)
				(type default)
			)
			(layer "F.Fab")
		)
		(fp_line
			(start 0.12065 -0.2794)
			(end 0.12065 -0.3048)
			(stroke
				(width 0.1)
				(type default)
			)
			(layer "F.Fab")
		)
		(fp_line
			(start 0.12065 -0.3048)
			(end 0.67945 -0.3048)
			(stroke
				(width 0.1)
				(type default)
			)
			(layer "F.Fab")
		)
		(fp_line
			(start 0.120396 0.3048)
			(end 0.120396 0.2794)
			(stroke
				(width 0.1)
				(type default)
			)
			(layer "F.Fab")
		)
		(fp_line
			(start 0.120396 0.2794)
			(end -0.12065 0.2794)
			(stroke
				(width 0.1)
				(type default)
			)
			(layer "F.Fab")
		)
		(fp_line
			(start -0.12065 0.3048)
			(end -0.67945 0.3048)
			(stroke
				(width 0.1)
				(type default)
			)
			(layer "F.Fab")
		)
		(fp_line
			(start -0.12065 0.2794)
			(end -0.12065 0.3048)
			(stroke
				(width 0.1)
				(type default)
			)
			(layer "F.Fab")
		)
		(fp_line
			(start -0.12065 -0.2794)
			(end 0.12065 -0.2794)
			(stroke
				(width 0.1)
				(type default)
			)
			(layer "F.Fab")
		)
		(fp_line
			(start -0.12065 -0.305054)
			(end -0.12065 -0.2794)
			(stroke
				(width 0.1)
				(type default)
			)
			(layer "F.Fab")
		)
		(fp_line
			(start -0.67945 0.3048)
			(end -0.67945 -0.305054)
			(stroke
				(width 0.1)
				(type default)
			)
			(layer "F.Fab")
		)
		(fp_line
			(start -0.67945 -0.305054)
			(end -0.12065 -0.305054)
			(stroke
				(width 0.1)
				(type default)
			)
			(layer "F.Fab")
		)
		(pad "1" smd circle
			(at -0.40005 0 180)
			(size 0 0)
			(layers "F.Cu" "F.Mask" "F.Paste")
			(net "FM_BOARD_SKU_ID3")
		)
		(pad "2" smd circle
			(at 0.40005 0 180)
			(size 0 0)
			(layers "F.Cu" "F.Mask" "F.Paste")
			(net "GND")
		)
	)
	(footprint ""
		(layer "F.Cu")
		(at 233.869738 -119.183658 -90)
		(property "Reference" "R3194"
			(at 0 0 270)
			(layer "F.SilkS")
			(hide yes)
			(effects
				(font
					(size 1.27 1.27)
				)
			)
		)
		(property "Value" ""
			(at 0 0 270)
			(layer "F.Fab")
			(effects
				(font
					(size 1.27 1.27)
				)
			)
		)
		(duplicate_pad_numbers_are_jumpers no)
		(fp_line
			(start -0.7874 0.4064)
			(end -0.7874 -0.109982)
			(stroke
				(width 0.1524)
				(type default)
			)
			(layer "F.SilkS")
		)
		(fp_line
			(start 0.7874 0.4064)
			(end -0.7874 0.4064)
			(stroke
				(width 0.1524)
				(type default)
			)
			(layer "F.SilkS")
		)
		(fp_line
			(start 0.7874 -0.089662)
			(end 0.7874 0.4064)
			(stroke
				(width 0.1524)
				(type default)
			)
			(layer "F.SilkS")
		)
		(fp_line
			(start -0.363982 -0.4064)
			(end 0.410718 -0.4064)
			(stroke
				(width 0.1524)
				(type default)
			)
			(layer "F.SilkS")
		)
		(fp_line
			(start -0.67945 0.3048)
			(end -0.67945 -0.305054)
			(stroke
				(width 0.1)
				(type default)
			)
			(layer "F.Fab")
		)
		(fp_line
			(start -0.12065 0.3048)
			(end -0.67945 0.3048)
			(stroke
				(width 0.1)
				(type default)
			)
			(layer "F.Fab")
		)
		(fp_line
			(start 0.120396 0.3048)
			(end 0.120396 0.2794)
			(stroke
				(width 0.1)
				(type default)
			)
			(layer "F.Fab")
		)
		(fp_line
			(start 0.67945 0.3048)
			(end 0.120396 0.3048)
			(stroke
				(width 0.1)
				(type default)
			)
			(layer "F.Fab")
		)
		(fp_line
			(start -0.12065 0.2794)
			(end -0.12065 0.3048)
			(stroke
				(width 0.1)
				(type default)
			)
			(layer "F.Fab")
		)
		(fp_line
			(start 0.120396 0.2794)
			(end -0.12065 0.2794)
			(stroke
				(width 0.1)
				(type default)
			)
			(layer "F.Fab")
		)
		(fp_line
			(start -0.12065 -0.2794)
			(end 0.12065 -0.2794)
			(stroke
				(width 0.1)
				(type default)
			)
			(layer "F.Fab")
		)
		(fp_line
			(start 0.12065 -0.2794)
			(end 0.12065 -0.3048)
			(stroke
				(width 0.1)
				(type default)
			)
			(layer "F.Fab")
		)
		(fp_line
			(start 0.12065 -0.3048)
			(end 0.67945 -0.3048)
			(stroke
				(width 0.1)
				(type default)
			)
			(layer "F.Fab")
		)
		(fp_line
			(start 0.67945 -0.3048)
			(end 0.67945 0.3048)
			(stroke
				(width 0.1)
				(type default)
			)
			(layer "F.Fab")
		)
		(fp_line
			(start -0.67945 -0.305054)
			(end -0.12065 -0.305054)
			(stroke
				(width 0.1)
				(type default)
			)
			(layer "F.Fab")
		)
		(fp_line
			(start -0.12065 -0.305054)
			(end -0.12065 -0.2794)
			(stroke
				(width 0.1)
				(type default)
			)
			(layer "F.Fab")
		)
		(pad "1" smd circle
			(at -0.40005 0 270)
			(size 0 0)
			(layers "F.Cu" "F.Mask" "F.Paste")
			(net "CLK_100M_OCP_V3_2_A_R_DP")
		)
		(pad "2" smd circle
			(at 0.40005 0 270)
			(size 0 0)
			(layers "F.Cu" "F.Mask" "F.Paste")
			(net "CLK_100M_OCP_V3_2_A_DP")
		)
	)
	(footprint ""
		(layer "F.Cu")
		(at 194.020186 -429.41113 -90)
		(property "Reference" "R2944"
			(at 0 0 270)
			(layer "F.SilkS")
			(hide yes)
			(effects
				(font
					(size 1.27 1.27)
				)
			)
		)
		(property "Value" ""
			(at 0 0 270)
			(layer "F.Fab")
			(effects
				(font
					(size 1.27 1.27)
				)
			)
		)
		(duplicate_pad_numbers_are_jumpers no)
		(fp_line
			(start -0.7874 0.4064)
			(end -0.7874 -0.4064)
			(stroke
				(width 0.1524)
				(type default)
			)
			(layer "F.SilkS")
		)
		(fp_line
			(start 0.7874 0.4064)
			(end -0.7874 0.4064)
			(stroke
				(width 0.1524)
				(type default)
			)
			(layer "F.SilkS")
		)
		(fp_line
			(start -0.7874 -0.4064)
			(end 0.7874 -0.4064)
			(stroke
				(width 0.1524)
				(type default)
			)
			(layer "F.SilkS")
		)
		(fp_line
			(start 0.7874 -0.4064)
			(end 0.7874 0.4064)
			(stroke
				(width 0.1524)
				(type default)
			)
			(layer "F.SilkS")
		)
		(fp_line
			(start -0.67945 0.3048)
			(end -0.67945 -0.305054)
			(stroke
				(width 0.1)
				(type default)
			)
			(layer "F.Fab")
		)
		(fp_line
			(start -0.12065 0.3048)
			(end -0.67945 0.3048)
			(stroke
				(width 0.1)
				(type default)
			)
			(layer "F.Fab")
		)
		(fp_line
			(start 0.120396 0.3048)
			(end 0.120396 0.2794)
			(stroke
				(width 0.1)
				(type default)
			)
			(layer "F.Fab")
		)
		(fp_line
			(start 0.67945 0.3048)
			(end 0.120396 0.3048)
			(stroke
				(width 0.1)
				(type default)
			)
			(layer "F.Fab")
		)
		(fp_line
			(start -0.12065 0.2794)
			(end -0.12065 0.3048)
			(stroke
				(width 0.1)
				(type default)
			)
			(layer "F.Fab")
		)
		(fp_line
			(start 0.120396 0.2794)
			(end -0.12065 0.2794)
			(stroke
				(width 0.1)
				(type default)
			)
			(layer "F.Fab")
		)
		(fp_line
			(start -0.12065 -0.2794)
			(end 0.12065 -0.2794)
			(stroke
				(width 0.1)
				(type default)
			)
			(layer "F.Fab")
		)
		(fp_line
			(start 0.12065 -0.2794)
			(end 0.12065 -0.3048)
			(stroke
				(width 0.1)
				(type default)
			)
			(layer "F.Fab")
		)
		(fp_line
			(start 0.12065 -0.3048)
			(end 0.67945 -0.3048)
			(stroke
				(width 0.1)
				(type default)
			)
			(layer "F.Fab")
		)
		(fp_line
			(start 0.67945 -0.3048)
			(end 0.67945 0.3048)
			(stroke
				(width 0.1)
				(type default)
			)
			(layer "F.Fab")
		)
		(fp_line
			(start -0.67945 -0.305054)
			(end -0.12065 -0.305054)
			(stroke
				(width 0.1)
				(type default)
			)
			(layer "F.Fab")
		)
		(fp_line
			(start -0.12065 -0.305054)
			(end -0.12065 -0.2794)
			(stroke
				(width 0.1)
				(type default)
			)
			(layer "F.Fab")
		)
		(pad "1" smd circle
			(at -0.40005 0 270)
			(size 0 0)
			(layers "F.Cu" "F.Mask" "F.Paste")
			(net "FM_GPU_HSC_EN_BUF_R")
		)
		(pad "2" smd circle
			(at 0.40005 0 270)
			(size 0 0)
			(layers "F.Cu" "F.Mask" "F.Paste")
			(net "FM_GPU_HSC_EN_BUF")
		)
	)
	(footprint ""
		(layer "F.Cu")
		(at 257.85953 -53.447442)
		(property "Reference" "PC2202"
			(at 0 0 0)
			(layer "F.SilkS")
			(hide yes)
			(effects
				(font
					(size 1.27 1.27)
				)
			)
		)
		(property "Value" ""
			(at 0 0 0)
			(layer "F.Fab")
			(effects
				(font
					(size 1.27 1.27)
				)
			)
		)
		(duplicate_pad_numbers_are_jumpers no)
		(fp_line
			(start -0.7874 -0.4064)
			(end 0.7874 -0.4064)
			(stroke
				(width 0.1524)
				(type default)
			)
			(layer "F.SilkS")
		)
		(fp_line
			(start -0.7874 0.4064)
			(end -0.7874 -0.4064)
			(stroke
				(width 0.1524)
				(type default)
			)
			(layer "F.SilkS")
		)
		(fp_line
			(start 0.7874 -0.4064)
			(end 0.7874 0.4064)
			(stroke
				(width 0.1524)
				(type default)
			)
			(layer "F.SilkS")
		)
		(fp_line
			(start 0.7874 0.4064)
			(end -0.7874 0.4064)
			(stroke
				(width 0.1524)
				(type default)
			)
			(layer "F.SilkS")
		)
		(fp_line
			(start -0.67945 -0.305054)
			(end -0.12065 -0.305054)
			(stroke
				(width 0.1)
				(type default)
			)
			(layer "F.Fab")
		)
		(fp_line
			(start -0.67945 0.3048)
			(end -0.67945 -0.305054)
			(stroke
				(width 0.1)
				(type default)
			)
			(layer "F.Fab")
		)
		(fp_line
			(start -0.12065 -0.305054)
			(end -0.12065 -0.2794)
			(stroke
				(width 0.1)
				(type default)
			)
			(layer "F.Fab")
		)
		(fp_line
			(start -0.12065 -0.2794)
			(end 0.12065 -0.2794)
			(stroke
				(width 0.1)
				(type default)
			)
			(layer "F.Fab")
		)
		(fp_line
			(start -0.12065 0.2794)
			(end -0.12065 0.3048)
			(stroke
				(width 0.1)
				(type default)
			)
			(layer "F.Fab")
		)
		(fp_line
			(start -0.12065 0.3048)
			(end -0.67945 0.3048)
			(stroke
				(width 0.1)
				(type default)
			)
			(layer "F.Fab")
		)
		(fp_line
			(start 0.120396 0.2794)
			(end -0.12065 0.2794)
			(stroke
				(width 0.1)
				(type default)
			)
			(layer "F.Fab")
		)
		(fp_line
			(start 0.120396 0.3048)
			(end 0.120396 0.2794)
			(stroke
				(width 0.1)
				(type default)
			)
			(layer "F.Fab")
		)
		(fp_line
			(start 0.12065 -0.3048)
			(end 0.67945 -0.3048)
			(stroke
				(width 0.1)
				(type default)
			)
			(layer "F.Fab")
		)
		(fp_line
			(start 0.12065 -0.2794)
			(end 0.12065 -0.3048)
			(stroke
				(width 0.1)
				(type default)
			)
			(layer "F.Fab")
		)
		(fp_line
			(start 0.67945 -0.3048)
			(end 0.67945 0.3048)
			(stroke
				(width 0.1)
				(type default)
			)
			(layer "F.Fab")
		)
		(fp_line
			(start 0.67945 0.3048)
			(end 0.120396 0.3048)
			(stroke
				(width 0.1)
				(type default)
			)
			(layer "F.Fab")
		)
		(pad "1" smd circle
			(at -0.40005 0)
			(size 0 0)
			(layers "F.Cu" "F.Mask" "F.Paste")
			(net "P12V_E1S_IMON_0")
		)
		(pad "2" smd circle
			(at 0.40005 0)
			(size 0 0)
			(layers "F.Cu" "F.Mask" "F.Paste")
			(net "GND")
		)
	)
	(footprint ""
		(layer "F.Cu")
		(at 152.96388 -128.742948 180)
		(property "Reference" "R3205"
			(at 0 0 180)
			(layer "F.SilkS")
			(hide yes)
			(effects
				(font
					(size 1.27 1.27)
				)
			)
		)
		(property "Value" ""
			(at 0 0 180)
			(layer "F.Fab")
			(effects
				(font
					(size 1.27 1.27)
				)
			)
		)
		(duplicate_pad_numbers_are_jumpers no)
		(fp_line
			(start 0.7874 0.4064)
			(end -0.7874 0.4064)
			(stroke
				(width 0.1524)
				(type default)
			)
			(layer "F.SilkS")
		)
		(fp_line
			(start 0.7874 -0.4064)
			(end 0.7874 0.4064)
			(stroke
				(width 0.1524)
				(type default)
			)
			(layer "F.SilkS")
		)
		(fp_line
			(start -0.7874 0.4064)
			(end -0.7874 -0.4064)
			(stroke
				(width 0.1524)
				(type default)
			)
			(layer "F.SilkS")
		)
		(fp_line
			(start -0.7874 -0.4064)
			(end 0.7874 -0.4064)
			(stroke
				(width 0.1524)
				(type default)
			)
			(layer "F.SilkS")
		)
		(fp_line
			(start 0.67945 0.3048)
			(end 0.120396 0.3048)
			(stroke
				(width 0.1)
				(type default)
			)
			(layer "F.Fab")
		)
		(fp_line
			(start 0.67945 -0.3048)
			(end 0.67945 0.3048)
			(stroke
				(width 0.1)
				(type default)
			)
			(layer "F.Fab")
		)
		(fp_line
			(start 0.12065 -0.2794)
			(end 0.12065 -0.3048)
			(stroke
				(width 0.1)
				(type default)
			)
			(layer "F.Fab")
		)
		(fp_line
			(start 0.12065 -0.3048)
			(end 0.67945 -0.3048)
			(stroke
				(width 0.1)
				(type default)
			)
			(layer "F.Fab")
		)
		(fp_line
			(start 0.120396 0.3048)
			(end 0.120396 0.2794)
			(stroke
				(width 0.1)
				(type default)
			)
			(layer "F.Fab")
		)
		(fp_line
			(start 0.120396 0.2794)
			(end -0.12065 0.2794)
			(stroke
				(width 0.1)
				(type default)
			)
			(layer "F.Fab")
		)
		(fp_line
			(start -0.12065 0.3048)
			(end -0.67945 0.3048)
			(stroke
				(width 0.1)
				(type default)
			)
			(layer "F.Fab")
		)
		(fp_line
			(start -0.12065 0.2794)
			(end -0.12065 0.3048)
			(stroke
				(width 0.1)
				(type default)
			)
			(layer "F.Fab")
		)
		(fp_line
			(start -0.12065 -0.2794)
			(end 0.12065 -0.2794)
			(stroke
				(width 0.1)
				(type default)
			)
			(layer "F.Fab")
		)
		(fp_line
			(start -0.12065 -0.305054)
			(end -0.12065 -0.2794)
			(stroke
				(width 0.1)
				(type default)
			)
			(layer "F.Fab")
		)
		(fp_line
			(start -0.67945 0.3048)
			(end -0.67945 -0.305054)
			(stroke
				(width 0.1)
				(type default)
			)
			(layer "F.Fab")
		)
		(fp_line
			(start -0.67945 -0.305054)
			(end -0.12065 -0.305054)
			(stroke
				(width 0.1)
				(type default)
			)
			(layer "F.Fab")
		)
		(pad "1" smd circle
			(at -0.40005 0 180)
			(size 0 0)
			(layers "F.Cu" "F.Mask" "F.Paste")
			(net "FB_BMC_ISOLATE_R2")
		)
		(pad "2" smd circle
			(at 0.40005 0 180)
			(size 0 0)
			(layers "F.Cu" "F.Mask" "F.Paste")
			(net "FB_BMC_ISOLATE1")
		)
	)
)
